FILE_TYPE = MULTI_PHYS_TABLE;
PART 'LCMXO2_A'
{=============================================================================================================================================================================================================================}
:PACK_TYPE  | MATERIAL  | PART_NUMBER    = EnvComp                  | PART_NUMBER    | JEDEC_TYPE        | CLASS | DESCRIPTION                                               |  HEIGHT     | COMPONENT_TYPE  | LPID  | SPEED_URL | Status |RPL| AML | Bus_Unit | Days ;
{=============================================================================================================================================================================================================================}
'256BGA'    |'IC'       |'H63395-001'(!) = ''                       | 'H63395-001'   | 'BGA256_1_8MA'    |'IC'   |'(USE SYM_4-6)IC,PLD,BLANK,256FBGA,LCMXO2,4GRD,3.3V'       | '0.067 IN'  | 'BGA'           |'3782' | 'http://speed.intel.com:8081/speed/module/pdm/item/pdm_item_detail_direct.asp?item_cde=H63395-001&item_rev=01&url_param=unused' | '' | '' | '' | '' | '' 
'256BGA'    |'EMPTY'    |'H63395-001'(!) = ''                       | 'H63395-001'   | 'BGA256_1_8MA'    |'IO'   |'(USE SYM_4-6)IC,PLD,BLANK,256FBGA,LCMXO2,4GRD,3.3V'       | '0.067 IN'  | 'BGA'           |'3782' | 'http://speed.intel.com:8081/speed/module/pdm/item/pdm_item_detail_direct.asp?item_cde=H63395-001&item_rev=01&url_param=unused' | '' | '' | '' | '' | ''
END_PART
END.
